(kicad_pcb
	(version 20260206)
	(generator "pcbnew")
	(generator_version "10.0")
	(general
		(thickness 1.6)
		(legacy_teardrops no)
	)
	(paper "A4")
	(title_block
		(title "panther-plus-userver — 13130-1b_20150205.brd")
		(comment 1 "Honey Badger (Wiwynn) / footprints 1352-1359 of 1509")
	)
	(layers
		(0 "F.Cu" signal "TOP")
		(4 "In1.Cu" signal "L2")
		(6 "In2.Cu" signal "L3")
		(8 "In3.Cu" signal "L4")
		(10 "In4.Cu" signal "L5")
		(12 "In5.Cu" signal "L6")
		(14 "In6.Cu" signal "L7")
		(16 "In7.Cu" signal "L8")
		(18 "In8.Cu" signal "L9")
		(20 "In9.Cu" signal "L10")
		(22 "In10.Cu" signal "L11")
		(2 "B.Cu" signal "BOTTOM")
		(9 "F.Adhes" user "F.Adhesive")
		(11 "B.Adhes" user "B.Adhesive")
		(13 "F.Paste" user "Package Geometry/Pastemask Top")
		(15 "B.Paste" user "Package Geometry/Pastemask Bottom")
		(5 "F.SilkS" user "Ref Des/Silkscreen Top")
		(7 "B.SilkS" user "Ref Des/Silkscreen Bottom")
		(1 "F.Mask" user "Board Geometry/Soldermask Top")
		(3 "B.Mask" user "Board Geometry/Soldermask Bottom")
		(17 "Dwgs.User" user "User.Drawings")
		(19 "Cmts.User" user "User.Comments")
		(21 "Eco1.User" user "User.Eco1")
		(23 "Eco2.User" user "User.Eco2")
		(25 "Edge.Cuts" user "Board Geometry/Outline")
		(27 "Margin" user)
		(31 "F.CrtYd" user "Package Geometry/Place Bound Top")
		(29 "B.CrtYd" user "Package Geometry/Place Bound Bottom")
		(35 "F.Fab" user "Ref Des/Assembly Top")
		(33 "B.Fab" user "Ref Des/Assembly Bottom")
	)
	(footprint ""
		(layer "B.Cu")
		(at 43.1038 -28.7528 90)
		(property "Reference" "R431"
			(at 0 0 90)
			(layer "B.SilkS")
			(hide yes)
			(effects
				(font
					(size 1.27 1.27)
				)
				(justify mirror)
			)
		)
		(property "Value" "43D2R2F-GP"
			(at -1.7907 -1.1176 90)
			(unlocked yes)
			(layer "B.Fab")
			(hide yes)
			(effects
				(font
					(size 1.016 1.016)
					(thickness 0.1524)
				)
				(justify mirror)
			)
		)
		(property "Device Type" "R402H16"
			(at -1.7907 -2.6416 90)
			(unlocked yes)
			(layer "B.Fab")
			(hide yes)
			(effects
				(font
					(size 1.016 1.016)
					(thickness 0.1524)
				)
				(justify mirror)
			)
		)
		(duplicate_pad_numbers_are_jumpers no)
		(fp_rect
			(start 0.381 0.8382)
			(end -0.381 -0.8382)
			(stroke
				(width 0)
				(type default)
			)
			(fill no)
			(layer "B.CrtYd")
		)
		(fp_rect
			(start 0.381 0.8382)
			(end -0.381 -0.8382)
			(stroke
				(width 0)
				(type default)
			)
			(fill no)
			(layer "B.Fab")
		)
		(pad "1" smd custom
			(at 0 -0.4318 270)
			(size 0.127 0.127)
			(layers "B.Cu" "B.Mask" "B.Paste")
			(net "CLK_100M_CLKBUFF_PCIE_DP")
			(options
				(clearance outline)
				(anchor circle)
			)
			(primitives
				(gr_poly
					(pts
						(arc
							(start -0.2032 0.2794)
							(mid -0.239121 0.264521)
							(end -0.254 0.2286)
						)
						(arc
							(start -0.254 -0.2286)
							(mid -0.239121 -0.264521)
							(end -0.2032 -0.2794)
						)
						(arc
							(start 0.2032 -0.2794)
							(mid 0.239121 -0.264521)
							(end 0.254 -0.2286)
						)
						(arc
							(start 0.254 0.2286)
							(mid 0.239121 0.264521)
							(end 0.2032 0.2794)
						)
					)
					(width 0)
					(fill yes)
				)
			)
		)
		(pad "2" smd custom
			(at 0 0.4318 270)
			(size 0.127 0.127)
			(layers "B.Cu" "B.Mask" "B.Paste")
			(net "GND")
			(options
				(clearance outline)
				(anchor circle)
			)
			(primitives
				(gr_poly
					(pts
						(arc
							(start -0.2032 0.2794)
							(mid -0.239121 0.264521)
							(end -0.254 0.2286)
						)
						(arc
							(start -0.254 -0.2286)
							(mid -0.239121 -0.264521)
							(end -0.2032 -0.2794)
						)
						(arc
							(start 0.2032 -0.2794)
							(mid 0.239121 -0.264521)
							(end 0.254 -0.2286)
						)
						(arc
							(start 0.254 0.2286)
							(mid 0.239121 0.264521)
							(end 0.2032 0.2794)
						)
					)
					(width 0)
					(fill yes)
				)
			)
		)
	)
	(footprint ""
		(layer "B.Cu")
		(at 144.4244 -47.498 90)
		(property "Reference" "R492"
			(at 0 0 90)
			(layer "B.SilkS")
			(hide yes)
			(effects
				(font
					(size 1.27 1.27)
				)
				(justify mirror)
			)
		)
		(property "Value" "1KR2F-3-GP"
			(at -1.7907 -1.1176 90)
			(unlocked yes)
			(layer "B.Fab")
			(hide yes)
			(effects
				(font
					(size 1.016 1.016)
					(thickness 0.1524)
				)
				(justify mirror)
			)
		)
		(property "Device Type" "R402H16"
			(at -1.7907 -2.6416 90)
			(unlocked yes)
			(layer "B.Fab")
			(hide yes)
			(effects
				(font
					(size 1.016 1.016)
					(thickness 0.1524)
				)
				(justify mirror)
			)
		)
		(duplicate_pad_numbers_are_jumpers no)
		(fp_rect
			(start 0.381 0.8382)
			(end -0.381 -0.8382)
			(stroke
				(width 0)
				(type default)
			)
			(fill no)
			(layer "B.CrtYd")
		)
		(fp_rect
			(start 0.381 0.8382)
			(end -0.381 -0.8382)
			(stroke
				(width 0)
				(type default)
			)
			(fill no)
			(layer "B.Fab")
		)
		(pad "1" smd custom
			(at 0 -0.4318 270)
			(size 0.127 0.127)
			(layers "B.Cu" "B.Mask" "B.Paste")
			(net "P3V3_STBY")
			(options
				(clearance outline)
				(anchor circle)
			)
			(primitives
				(gr_poly
					(pts
						(arc
							(start -0.2032 0.2794)
							(mid -0.239121 0.264521)
							(end -0.254 0.2286)
						)
						(arc
							(start -0.254 -0.2286)
							(mid -0.239121 -0.264521)
							(end -0.2032 -0.2794)
						)
						(arc
							(start 0.2032 -0.2794)
							(mid 0.239121 -0.264521)
							(end 0.254 -0.2286)
						)
						(arc
							(start 0.254 0.2286)
							(mid 0.239121 0.264521)
							(end 0.2032 0.2794)
						)
					)
					(width 0)
					(fill yes)
				)
			)
		)
		(pad "2" smd custom
			(at 0 0.4318 270)
			(size 0.127 0.127)
			(layers "B.Cu" "B.Mask" "B.Paste")
			(net "JTAG_PLD_TCK")
			(options
				(clearance outline)
				(anchor circle)
			)
			(primitives
				(gr_poly
					(pts
						(arc
							(start -0.2032 0.2794)
							(mid -0.239121 0.264521)
							(end -0.254 0.2286)
						)
						(arc
							(start -0.254 -0.2286)
							(mid -0.239121 -0.264521)
							(end -0.2032 -0.2794)
						)
						(arc
							(start 0.2032 -0.2794)
							(mid 0.239121 -0.264521)
							(end 0.254 -0.2286)
						)
						(arc
							(start 0.254 0.2286)
							(mid 0.239121 0.264521)
							(end 0.2032 0.2794)
						)
					)
					(width 0)
					(fill yes)
				)
			)
		)
	)
	(footprint ""
		(layer "B.Cu")
		(at 22.4028 -61.087 180)
		(property "Reference" "PR27"
			(at 0 0 0)
			(layer "B.SilkS")
			(hide yes)
			(effects
				(font
					(size 1.27 1.27)
				)
				(justify mirror)
			)
		)
		(property "Value" "2MR2F-GP"
			(at -1.7907 -1.1176 180)
			(unlocked yes)
			(layer "B.Fab")
			(hide yes)
			(effects
				(font
					(size 1.016 1.016)
					(thickness 0.1524)
				)
				(justify mirror)
			)
		)
		(property "Device Type" "R402H16"
			(at -1.7907 -2.6416 180)
			(unlocked yes)
			(layer "B.Fab")
			(hide yes)
			(effects
				(font
					(size 1.016 1.016)
					(thickness 0.1524)
				)
				(justify mirror)
			)
		)
		(duplicate_pad_numbers_are_jumpers no)
		(fp_rect
			(start 0.381 0.8382)
			(end -0.381 -0.8382)
			(stroke
				(width 0)
				(type default)
			)
			(fill no)
			(layer "B.CrtYd")
		)
		(fp_rect
			(start 0.381 0.8382)
			(end -0.381 -0.8382)
			(stroke
				(width 0)
				(type default)
			)
			(fill no)
			(layer "B.Fab")
		)
		(pad "1" smd custom
			(at 0 -0.4318)
			(size 0.127 0.127)
			(layers "B.Cu" "B.Mask" "B.Paste")
			(net "GND")
			(options
				(clearance outline)
				(anchor circle)
			)
			(primitives
				(gr_poly
					(pts
						(arc
							(start -0.2032 0.2794)
							(mid -0.239121 0.264521)
							(end -0.254 0.2286)
						)
						(arc
							(start -0.254 -0.2286)
							(mid -0.239121 -0.264521)
							(end -0.2032 -0.2794)
						)
						(arc
							(start 0.2032 -0.2794)
							(mid 0.239121 -0.264521)
							(end 0.254 -0.2286)
						)
						(arc
							(start 0.254 0.2286)
							(mid 0.239121 0.264521)
							(end 0.2032 0.2794)
						)
					)
					(width 0)
					(fill yes)
				)
			)
		)
		(pad "2" smd custom
			(at 0 0.4318)
			(size 0.127 0.127)
			(layers "B.Cu" "B.Mask" "B.Paste")
			(net "VR_PVNN_ISUMP")
			(options
				(clearance outline)
				(anchor circle)
			)
			(primitives
				(gr_poly
					(pts
						(arc
							(start -0.2032 0.2794)
							(mid -0.239121 0.264521)
							(end -0.254 0.2286)
						)
						(arc
							(start -0.254 -0.2286)
							(mid -0.239121 -0.264521)
							(end -0.2032 -0.2794)
						)
						(arc
							(start 0.2032 -0.2794)
							(mid 0.239121 -0.264521)
							(end 0.254 -0.2286)
						)
						(arc
							(start 0.254 0.2286)
							(mid 0.239121 0.264521)
							(end 0.2032 0.2794)
						)
					)
					(width 0)
					(fill yes)
				)
			)
		)
	)
	(footprint ""
		(layer "B.Cu")
		(at 88.9 -33.274)
		(property "Reference" "R485"
			(at 0 0 0)
			(layer "B.SilkS")
			(hide yes)
			(effects
				(font
					(size 1.27 1.27)
				)
				(justify mirror)
			)
		)
		(property "Value" "4K7R2F-GP"
			(at -1.7907 -1.1176 0)
			(unlocked yes)
			(layer "B.Fab")
			(hide yes)
			(effects
				(font
					(size 1.016 1.016)
					(thickness 0.1524)
				)
				(justify mirror)
			)
		)
		(property "Device Type" "R402H16"
			(at -1.7907 -2.6416 0)
			(unlocked yes)
			(layer "B.Fab")
			(hide yes)
			(effects
				(font
					(size 1.016 1.016)
					(thickness 0.1524)
				)
				(justify mirror)
			)
		)
		(duplicate_pad_numbers_are_jumpers no)
		(fp_rect
			(start 0.381 0.8382)
			(end -0.381 -0.8382)
			(stroke
				(width 0)
				(type default)
			)
			(fill no)
			(layer "B.CrtYd")
		)
		(fp_rect
			(start 0.381 0.8382)
			(end -0.381 -0.8382)
			(stroke
				(width 0)
				(type default)
			)
			(fill no)
			(layer "B.Fab")
		)
		(pad "1" smd custom
			(at 0 -0.4318 180)
			(size 0.127 0.127)
			(layers "B.Cu" "B.Mask" "B.Paste")
			(net "P3V3_CPU")
			(options
				(clearance outline)
				(anchor circle)
			)
			(primitives
				(gr_poly
					(pts
						(arc
							(start -0.2032 0.2794)
							(mid -0.239121 0.264521)
							(end -0.254 0.2286)
						)
						(arc
							(start -0.254 -0.2286)
							(mid -0.239121 -0.264521)
							(end -0.2032 -0.2794)
						)
						(arc
							(start 0.2032 -0.2794)
							(mid 0.239121 -0.264521)
							(end 0.254 -0.2286)
						)
						(arc
							(start 0.254 0.2286)
							(mid 0.239121 0.264521)
							(end 0.2032 0.2794)
						)
					)
					(width 0)
					(fill yes)
				)
			)
		)
		(pad "2" smd custom
			(at 0 0.4318 180)
			(size 0.127 0.127)
			(layers "B.Cu" "B.Mask" "B.Paste")
			(net "BD_REV_0")
			(options
				(clearance outline)
				(anchor circle)
			)
			(primitives
				(gr_poly
					(pts
						(arc
							(start -0.2032 0.2794)
							(mid -0.239121 0.264521)
							(end -0.254 0.2286)
						)
						(arc
							(start -0.254 -0.2286)
							(mid -0.239121 -0.264521)
							(end -0.2032 -0.2794)
						)
						(arc
							(start 0.2032 -0.2794)
							(mid 0.239121 -0.264521)
							(end 0.254 -0.2286)
						)
						(arc
							(start 0.254 0.2286)
							(mid 0.239121 0.264521)
							(end 0.2032 0.2794)
						)
					)
					(width 0)
					(fill yes)
				)
			)
		)
	)
	(footprint ""
		(layer "B.Cu")
		(at 185.039 -13.716 90)
		(property "Reference" "PC206"
			(at 0 0 90)
			(layer "B.SilkS")
			(hide yes)
			(effects
				(font
					(size 1.27 1.27)
				)
				(justify mirror)
			)
		)
		(property "Value" "SC10U6D3V3MX-GP"
			(at 0 -2.8194 90)
			(unlocked yes)
			(layer "B.Fab")
			(hide yes)
			(effects
				(font
					(size 1.016 1.016)
					(thickness 0.1524)
				)
				(justify mirror)
			)
		)
		(property "Device Type" "C603H38"
			(at 0 -4.3434 90)
			(unlocked yes)
			(layer "B.Fab")
			(hide yes)
			(effects
				(font
					(size 1.016 1.016)
					(thickness 0.1524)
				)
				(justify mirror)
			)
		)
		(duplicate_pad_numbers_are_jumpers no)
		(fp_line
			(start 0.4064 0)
			(end -0.4064 0)
			(stroke
				(width 0.2286)
				(type default)
			)
			(layer "B.SilkS")
		)
		(fp_rect
			(start 0.635 1.1811)
			(end -0.635 -1.1811)
			(stroke
				(width 0)
				(type default)
			)
			(fill no)
			(layer "B.CrtYd")
		)
		(fp_rect
			(start 0.635 1.1811)
			(end -0.635 -1.1811)
			(stroke
				(width 0)
				(type default)
			)
			(fill no)
			(layer "B.Fab")
		)
		(pad "1" smd custom
			(at 0 -0.6604 270)
			(size 0.19685 0.19685)
			(layers "B.Cu" "B.Mask" "B.Paste")
			(net "GND")
			(options
				(clearance outline)
				(anchor circle)
			)
			(primitives
				(gr_poly
					(pts
						(arc
							(start 0.508 0.2921)
							(mid 0.478242 0.363942)
							(end 0.4064 0.3937)
						)
						(arc
							(start -0.4064 0.3937)
							(mid -0.478242 0.363942)
							(end -0.508 0.2921)
						)
						(arc
							(start -0.508 -0.2921)
							(mid -0.478242 -0.363942)
							(end -0.4064 -0.3937)
						)
						(arc
							(start 0.4064 -0.3937)
							(mid 0.478242 -0.363942)
							(end 0.508 -0.2921)
						)
					)
					(width 0)
					(fill yes)
				)
			)
		)
		(pad "2" smd custom
			(at 0 0.6604 270)
			(size 0.19685 0.19685)
			(layers "B.Cu" "B.Mask" "B.Paste")
			(net "PV_VTT_DDR_B")
			(options
				(clearance outline)
				(anchor circle)
			)
			(primitives
				(gr_poly
					(pts
						(arc
							(start 0.508 0.2921)
							(mid 0.478242 0.363942)
							(end 0.4064 0.3937)
						)
						(arc
							(start -0.4064 0.3937)
							(mid -0.478242 0.363942)
							(end -0.508 0.2921)
						)
						(arc
							(start -0.508 -0.2921)
							(mid -0.478242 -0.363942)
							(end -0.4064 -0.3937)
						)
						(arc
							(start 0.4064 -0.3937)
							(mid 0.478242 -0.363942)
							(end 0.508 -0.2921)
						)
					)
					(width 0)
					(fill yes)
				)
			)
		)
	)
	(footprint ""
		(layer "B.Cu")
		(at 104.013 -51.451002 180)
		(property "Reference" "C123"
			(at 0 0 0)
			(layer "B.SilkS")
			(hide yes)
			(effects
				(font
					(size 1.27 1.27)
				)
				(justify mirror)
			)
		)
		(property "Value" "SC1U10V2KX-1GP"
			(at -1.1811 -2.7051 180)
			(unlocked yes)
			(layer "B.Fab")
			(hide yes)
			(effects
				(font
					(size 1.016 1.016)
					(thickness 0.1524)
				)
				(justify mirror)
			)
		)
		(property "Device Type" "C402H22"
			(at -1.1811 -4.2291 180)
			(unlocked yes)
			(layer "B.Fab")
			(hide yes)
			(effects
				(font
					(size 1.016 1.016)
					(thickness 0.1524)
				)
				(justify mirror)
			)
		)
		(duplicate_pad_numbers_are_jumpers no)
		(fp_rect
			(start 0.381 0.7366)
			(end -0.381 -0.7366)
			(stroke
				(width 0)
				(type default)
			)
			(fill no)
			(layer "B.CrtYd")
		)
		(fp_rect
			(start 0.381 0.7366)
			(end -0.381 -0.7366)
			(stroke
				(width 0)
				(type default)
			)
			(fill no)
			(layer "B.Fab")
		)
		(pad "1" smd custom
			(at 0 -0.4572)
			(size 0.1143 0.1143)
			(layers "B.Cu" "B.Mask" "B.Paste")
			(net "PV_VDDR")
			(options
				(clearance outline)
				(anchor circle)
			)
			(primitives
				(gr_poly
					(pts
						(arc
							(start -0.254 0.1778)
							(mid -0.239121 0.213721)
							(end -0.2032 0.2286)
						)
						(arc
							(start 0.2032 0.2286)
							(mid 0.239121 0.213721)
							(end 0.254 0.1778)
						)
						(arc
							(start 0.254 -0.1778)
							(mid 0.239121 -0.213721)
							(end 0.2032 -0.2286)
						)
						(arc
							(start -0.2032 -0.2286)
							(mid -0.239121 -0.213721)
							(end -0.254 -0.1778)
						)
					)
					(width 0)
					(fill yes)
				)
			)
		)
		(pad "2" smd custom
			(at 0 0.4572)
			(size 0.1143 0.1143)
			(layers "B.Cu" "B.Mask" "B.Paste")
			(net "GND")
			(options
				(clearance outline)
				(anchor circle)
			)
			(primitives
				(gr_poly
					(pts
						(arc
							(start -0.254 0.1778)
							(mid -0.239121 0.213721)
							(end -0.2032 0.2286)
						)
						(arc
							(start 0.2032 0.2286)
							(mid 0.239121 0.213721)
							(end 0.254 0.1778)
						)
						(arc
							(start 0.254 -0.1778)
							(mid 0.239121 -0.213721)
							(end 0.2032 -0.2286)
						)
						(arc
							(start -0.2032 -0.2286)
							(mid -0.239121 -0.213721)
							(end -0.254 -0.1778)
						)
					)
					(width 0)
					(fill yes)
				)
			)
		)
	)
	(footprint ""
		(layer "B.Cu")
		(at 132.715 -56.388 180)
		(property "Reference" "PC143"
			(at 0 0 0)
			(layer "B.SilkS")
			(hide yes)
			(effects
				(font
					(size 1.27 1.27)
				)
				(justify mirror)
			)
		)
		(property "Value" "SC10U6D3V3MX-GP"
			(at 0 -2.8194 180)
			(unlocked yes)
			(layer "B.Fab")
			(hide yes)
			(effects
				(font
					(size 1.016 1.016)
					(thickness 0.1524)
				)
				(justify mirror)
			)
		)
		(property "Device Type" "C603H38"
			(at 0 -4.3434 180)
			(unlocked yes)
			(layer "B.Fab")
			(hide yes)
			(effects
				(font
					(size 1.016 1.016)
					(thickness 0.1524)
				)
				(justify mirror)
			)
		)
		(duplicate_pad_numbers_are_jumpers no)
		(fp_line
			(start 0.4064 0)
			(end -0.4064 0)
			(stroke
				(width 0.2286)
				(type default)
			)
			(layer "B.SilkS")
		)
		(fp_rect
			(start 0.635 1.1811)
			(end -0.635 -1.1811)
			(stroke
				(width 0)
				(type default)
			)
			(fill no)
			(layer "B.CrtYd")
		)
		(fp_rect
			(start 0.635 1.1811)
			(end -0.635 -1.1811)
			(stroke
				(width 0)
				(type default)
			)
			(fill no)
			(layer "B.Fab")
		)
		(pad "1" smd custom
			(at 0 -0.6604)
			(size 0.19685 0.19685)
			(layers "B.Cu" "B.Mask" "B.Paste")
			(net "GND")
			(options
				(clearance outline)
				(anchor circle)
			)
			(primitives
				(gr_poly
					(pts
						(arc
							(start 0.508 0.2921)
							(mid 0.478242 0.363942)
							(end 0.4064 0.3937)
						)
						(arc
							(start -0.4064 0.3937)
							(mid -0.478242 0.363942)
							(end -0.508 0.2921)
						)
						(arc
							(start -0.508 -0.2921)
							(mid -0.478242 -0.363942)
							(end -0.4064 -0.3937)
						)
						(arc
							(start 0.4064 -0.3937)
							(mid 0.478242 -0.363942)
							(end 0.508 -0.2921)
						)
					)
					(width 0)
					(fill yes)
				)
			)
		)
		(pad "2" smd custom
			(at 0 0.6604)
			(size 0.19685 0.19685)
			(layers "B.Cu" "B.Mask" "B.Paste")
			(net "PV_VTT_DDR_A")
			(options
				(clearance outline)
				(anchor circle)
			)
			(primitives
				(gr_poly
					(pts
						(arc
							(start 0.508 0.2921)
							(mid 0.478242 0.363942)
							(end 0.4064 0.3937)
						)
						(arc
							(start -0.4064 0.3937)
							(mid -0.478242 0.363942)
							(end -0.508 0.2921)
						)
						(arc
							(start -0.508 -0.2921)
							(mid -0.478242 -0.363942)
							(end -0.4064 -0.3937)
						)
						(arc
							(start 0.4064 -0.3937)
							(mid 0.478242 -0.363942)
							(end 0.508 -0.2921)
						)
					)
					(width 0)
					(fill yes)
				)
			)
		)
	)
	(footprint ""
		(layer "B.Cu")
		(at 197.485 -31.115 -90)
		(property "Reference" "R149"
			(at 0 0 90)
			(layer "B.SilkS")
			(hide yes)
			(effects
				(font
					(size 1.27 1.27)
				)
				(justify mirror)
			)
		)
		(property "Value" "300R2F-GP"
			(at -1.7907 -1.1176 270)
			(unlocked yes)
			(layer "B.Fab")
			(hide yes)
			(effects
				(font
					(size 1.016 1.016)
					(thickness 0.1524)
				)
				(justify mirror)
			)
		)
		(property "Device Type" "R402H16"
			(at -1.7907 -2.6416 270)
			(unlocked yes)
			(layer "B.Fab")
			(hide yes)
			(effects
				(font
					(size 1.016 1.016)
					(thickness 0.1524)
				)
				(justify mirror)
			)
		)
		(duplicate_pad_numbers_are_jumpers no)
		(fp_rect
			(start 0.381 0.8382)
			(end -0.381 -0.8382)
			(stroke
				(width 0)
				(type default)
			)
			(fill no)
			(layer "B.CrtYd")
		)
		(fp_rect
			(start 0.381 0.8382)
			(end -0.381 -0.8382)
			(stroke
				(width 0)
				(type default)
			)
			(fill no)
			(layer "B.Fab")
		)
		(pad "1" smd custom
			(at 0 -0.4318 90)
			(size 0.127 0.127)
			(layers "B.Cu" "B.Mask" "B.Paste")
			(net "PORT80_R_BIT0")
			(options
				(clearance outline)
				(anchor circle)
			)
			(primitives
				(gr_poly
					(pts
						(arc
							(start -0.2032 0.2794)
							(mid -0.239121 0.264521)
							(end -0.254 0.2286)
						)
						(arc
							(start -0.254 -0.2286)
							(mid -0.239121 -0.264521)
							(end -0.2032 -0.2794)
						)
						(arc
							(start 0.2032 -0.2794)
							(mid 0.239121 -0.264521)
							(end 0.254 -0.2286)
						)
						(arc
							(start 0.254 0.2286)
							(mid 0.239121 0.264521)
							(end 0.2032 0.2794)
						)
					)
					(width 0)
					(fill yes)
				)
			)
		)
		(pad "2" smd custom
			(at 0 0.4318 90)
			(size 0.127 0.127)
			(layers "B.Cu" "B.Mask" "B.Paste")
			(net "P3V3_STBY")
			(options
				(clearance outline)
				(anchor circle)
			)
			(primitives
				(gr_poly
					(pts
						(arc
							(start -0.2032 0.2794)
							(mid -0.239121 0.264521)
							(end -0.254 0.2286)
						)
						(arc
							(start -0.254 -0.2286)
							(mid -0.239121 -0.264521)
							(end -0.2032 -0.2794)
						)
						(arc
							(start 0.2032 -0.2794)
							(mid 0.239121 -0.264521)
							(end 0.254 -0.2286)
						)
						(arc
							(start 0.254 0.2286)
							(mid 0.239121 0.264521)
							(end 0.2032 0.2794)
						)
					)
					(width 0)
					(fill yes)
				)
			)
		)
	)
)
